(kicad_pcb
	(version 20260206)
	(generator "pcbnew")
	(generator_version "10.0")
	(general
		(thickness 1.6)
		(legacy_teardrops no)
	)
	(paper "A4")
	(title_block
		(title "04192023_DAF0TMB3IC0_F0TG_MB_C_brd_V02_OCP.brd")
		(comment 1 "Grand Teton / footprints 2279-2285 of 8354")
	)
	(layers
		(0 "F.Cu" signal "TOP")
		(4 "In1.Cu" signal "GND")
		(6 "In2.Cu" signal "IN1")
		(8 "In3.Cu" signal "GND1")
		(10 "In4.Cu" signal "IN2")
		(12 "In5.Cu" signal "GND2")
		(14 "In6.Cu" signal "IN3")
		(16 "In7.Cu" signal "GND3")
		(18 "In8.Cu" signal "VCC")
		(20 "In9.Cu" signal "VCC1")
		(22 "In10.Cu" signal "GND4")
		(24 "In11.Cu" signal "IN4")
		(26 "In12.Cu" signal "GND5")
		(28 "In13.Cu" signal "IN5")
		(30 "In14.Cu" signal "GND6")
		(32 "In15.Cu" signal "IN6")
		(34 "In16.Cu" signal "GND7")
		(2 "B.Cu" signal "BOTTOM")
		(9 "F.Adhes" user "F.Adhesive")
		(11 "B.Adhes" user "B.Adhesive")
		(13 "F.Paste" user "Package Geometry/Pastemask Top")
		(15 "B.Paste" user "Package Geometry/Pastemask Bottom")
		(5 "F.SilkS" user "Ref Des/Silkscreen Top")
		(7 "B.SilkS" user "Ref Des/Silkscreen Bottom")
		(1 "F.Mask" user "Board Geometry/Soldermask Top")
		(3 "B.Mask" user "Board Geometry/Soldermask Bottom")
		(17 "Dwgs.User" user "User.Drawings")
		(19 "Cmts.User" user "User.Comments")
		(21 "Eco1.User" user "User.Eco1")
		(23 "Eco2.User" user "User.Eco2")
		(25 "Edge.Cuts" user "Board Geometry/Outline")
		(27 "Margin" user)
		(31 "F.CrtYd" user "Package Geometry/Place Bound Top")
		(29 "B.CrtYd" user "Package Geometry/Place Bound Bottom")
		(35 "F.Fab" user "Ref Des/Assembly Top")
		(33 "B.Fab" user "Ref Des/Assembly Bottom")
	)
	(footprint ""
		(layer "F.Cu")
		(at 442.077602 -429.37811 -90)
		(property "Reference" "R646"
			(at 0 0 270)
			(layer "F.SilkS")
			(hide yes)
			(effects
				(font
					(size 1.27 1.27)
				)
			)
		)
		(property "Value" ""
			(at 0 0 270)
			(layer "F.Fab")
			(effects
				(font
					(size 1.27 1.27)
				)
			)
		)
		(duplicate_pad_numbers_are_jumpers no)
		(fp_line
			(start -0.7874 0.4064)
			(end -0.7874 -0.4064)
			(stroke
				(width 0.1524)
				(type default)
			)
			(layer "F.SilkS")
		)
		(fp_line
			(start 0.7874 0.4064)
			(end -0.7874 0.4064)
			(stroke
				(width 0.1524)
				(type default)
			)
			(layer "F.SilkS")
		)
		(fp_line
			(start -0.7874 -0.4064)
			(end 0.7874 -0.4064)
			(stroke
				(width 0.1524)
				(type default)
			)
			(layer "F.SilkS")
		)
		(fp_line
			(start 0.7874 -0.4064)
			(end 0.7874 0.4064)
			(stroke
				(width 0.1524)
				(type default)
			)
			(layer "F.SilkS")
		)
		(fp_line
			(start -0.67945 0.3048)
			(end -0.67945 -0.305054)
			(stroke
				(width 0.1)
				(type default)
			)
			(layer "F.Fab")
		)
		(fp_line
			(start -0.12065 0.3048)
			(end -0.67945 0.3048)
			(stroke
				(width 0.1)
				(type default)
			)
			(layer "F.Fab")
		)
		(fp_line
			(start 0.120396 0.3048)
			(end 0.120396 0.2794)
			(stroke
				(width 0.1)
				(type default)
			)
			(layer "F.Fab")
		)
		(fp_line
			(start 0.67945 0.3048)
			(end 0.120396 0.3048)
			(stroke
				(width 0.1)
				(type default)
			)
			(layer "F.Fab")
		)
		(fp_line
			(start -0.12065 0.2794)
			(end -0.12065 0.3048)
			(stroke
				(width 0.1)
				(type default)
			)
			(layer "F.Fab")
		)
		(fp_line
			(start 0.120396 0.2794)
			(end -0.12065 0.2794)
			(stroke
				(width 0.1)
				(type default)
			)
			(layer "F.Fab")
		)
		(fp_line
			(start -0.12065 -0.2794)
			(end 0.12065 -0.2794)
			(stroke
				(width 0.1)
				(type default)
			)
			(layer "F.Fab")
		)
		(fp_line
			(start 0.12065 -0.2794)
			(end 0.12065 -0.3048)
			(stroke
				(width 0.1)
				(type default)
			)
			(layer "F.Fab")
		)
		(fp_line
			(start 0.12065 -0.3048)
			(end 0.67945 -0.3048)
			(stroke
				(width 0.1)
				(type default)
			)
			(layer "F.Fab")
		)
		(fp_line
			(start 0.67945 -0.3048)
			(end 0.67945 0.3048)
			(stroke
				(width 0.1)
				(type default)
			)
			(layer "F.Fab")
		)
		(fp_line
			(start -0.67945 -0.305054)
			(end -0.12065 -0.305054)
			(stroke
				(width 0.1)
				(type default)
			)
			(layer "F.Fab")
		)
		(fp_line
			(start -0.12065 -0.305054)
			(end -0.12065 -0.2794)
			(stroke
				(width 0.1)
				(type default)
			)
			(layer "F.Fab")
		)
		(pad "1" smd circle
			(at -0.40005 0 270)
			(size 0 0)
			(layers "F.Cu" "F.Mask" "F.Paste")
			(net "P0V9_RETIMER_CPU0_PMSCL")
		)
		(pad "2" smd circle
			(at 0.40005 0 270)
			(size 0 0)
			(layers "F.Cu" "F.Mask" "F.Paste")
			(net "P0V9_RETIMER_CPU0_PMSCL_R")
		)
	)
	(footprint ""
		(layer "F.Cu")
		(at 390.713722 -177.532284)
		(property "Reference" "PR347"
			(at 0 0 0)
			(layer "F.SilkS")
			(hide yes)
			(effects
				(font
					(size 1.27 1.27)
				)
			)
		)
		(property "Value" ""
			(at 0 0 0)
			(layer "F.Fab")
			(effects
				(font
					(size 1.27 1.27)
				)
			)
		)
		(duplicate_pad_numbers_are_jumpers no)
		(fp_line
			(start -0.7874 -0.4064)
			(end 0.7874 -0.4064)
			(stroke
				(width 0.1524)
				(type default)
			)
			(layer "F.SilkS")
		)
		(fp_line
			(start -0.7874 0.4064)
			(end -0.7874 -0.4064)
			(stroke
				(width 0.1524)
				(type default)
			)
			(layer "F.SilkS")
		)
		(fp_line
			(start 0.7874 -0.4064)
			(end 0.7874 0.4064)
			(stroke
				(width 0.1524)
				(type default)
			)
			(layer "F.SilkS")
		)
		(fp_line
			(start 0.7874 0.4064)
			(end -0.7874 0.4064)
			(stroke
				(width 0.1524)
				(type default)
			)
			(layer "F.SilkS")
		)
		(fp_line
			(start -0.67945 -0.305054)
			(end -0.12065 -0.305054)
			(stroke
				(width 0.1)
				(type default)
			)
			(layer "F.Fab")
		)
		(fp_line
			(start -0.67945 0.3048)
			(end -0.67945 -0.305054)
			(stroke
				(width 0.1)
				(type default)
			)
			(layer "F.Fab")
		)
		(fp_line
			(start -0.12065 -0.305054)
			(end -0.12065 -0.2794)
			(stroke
				(width 0.1)
				(type default)
			)
			(layer "F.Fab")
		)
		(fp_line
			(start -0.12065 -0.2794)
			(end 0.12065 -0.2794)
			(stroke
				(width 0.1)
				(type default)
			)
			(layer "F.Fab")
		)
		(fp_line
			(start -0.12065 0.2794)
			(end -0.12065 0.3048)
			(stroke
				(width 0.1)
				(type default)
			)
			(layer "F.Fab")
		)
		(fp_line
			(start -0.12065 0.3048)
			(end -0.67945 0.3048)
			(stroke
				(width 0.1)
				(type default)
			)
			(layer "F.Fab")
		)
		(fp_line
			(start 0.120396 0.2794)
			(end -0.12065 0.2794)
			(stroke
				(width 0.1)
				(type default)
			)
			(layer "F.Fab")
		)
		(fp_line
			(start 0.120396 0.3048)
			(end 0.120396 0.2794)
			(stroke
				(width 0.1)
				(type default)
			)
			(layer "F.Fab")
		)
		(fp_line
			(start 0.12065 -0.3048)
			(end 0.67945 -0.3048)
			(stroke
				(width 0.1)
				(type default)
			)
			(layer "F.Fab")
		)
		(fp_line
			(start 0.12065 -0.2794)
			(end 0.12065 -0.3048)
			(stroke
				(width 0.1)
				(type default)
			)
			(layer "F.Fab")
		)
		(fp_line
			(start 0.67945 -0.3048)
			(end 0.67945 0.3048)
			(stroke
				(width 0.1)
				(type default)
			)
			(layer "F.Fab")
		)
		(fp_line
			(start 0.67945 0.3048)
			(end 0.120396 0.3048)
			(stroke
				(width 0.1)
				(type default)
			)
			(layer "F.Fab")
		)
		(pad "1" smd circle
			(at -0.40005 0)
			(size 0 0)
			(layers "F.Cu" "F.Mask" "F.Paste")
			(net "GND")
		)
		(pad "2" smd circle
			(at 0.40005 0)
			(size 0 0)
			(layers "F.Cu" "F.Mask" "F.Paste")
			(net "PVDDCR_CPU0_P0_LSET4")
		)
	)
	(footprint ""
		(layer "F.Cu")
		(at 27.598878 -16.099536 90)
		(property "Reference" "C687"
			(at 0 0 90)
			(layer "F.SilkS")
			(hide yes)
			(effects
				(font
					(size 1.27 1.27)
				)
			)
		)
		(property "Value" ""
			(at 0 0 90)
			(layer "F.Fab")
			(effects
				(font
					(size 1.27 1.27)
				)
			)
		)
		(duplicate_pad_numbers_are_jumpers no)
		(fp_line
			(start 0.299974 -0.150114)
			(end 0.299974 0.150114)
			(stroke
				(width 0.1)
				(type default)
			)
			(layer "F.Fab")
		)
		(fp_line
			(start -0.299974 -0.150114)
			(end 0.299974 -0.150114)
			(stroke
				(width 0.1)
				(type default)
			)
			(layer "F.Fab")
		)
		(fp_line
			(start 0.299974 0.150114)
			(end -0.299974 0.150114)
			(stroke
				(width 0.1)
				(type default)
			)
			(layer "F.Fab")
		)
		(fp_line
			(start -0.299974 0.150114)
			(end -0.299974 -0.150114)
			(stroke
				(width 0.1)
				(type default)
			)
			(layer "F.Fab")
		)
		(pad "1" smd rect
			(at -0.2667 0 90)
			(size 0.3048 0.381)
			(layers "F.Cu" "F.Mask" "F.Paste")
			(net "P5E_CPU1_G1_TX_C_DP<11>")
		)
		(pad "2" smd rect
			(at 0.2667 0 90)
			(size 0.3048 0.381)
			(layers "F.Cu" "F.Mask" "F.Paste")
			(net "P5E_CPU1_G1_TX_DP<11>")
		)
	)
	(footprint ""
		(layer "F.Cu")
		(at 265.201908 -418.13607)
		(property "Reference" "R4901"
			(at 0 0 0)
			(layer "F.SilkS")
			(hide yes)
			(effects
				(font
					(size 1.27 1.27)
				)
			)
		)
		(property "Value" ""
			(at 0 0 0)
			(layer "F.Fab")
			(effects
				(font
					(size 1.27 1.27)
				)
			)
		)
		(duplicate_pad_numbers_are_jumpers no)
		(fp_line
			(start -0.7874 -0.4064)
			(end 0.7874 -0.4064)
			(stroke
				(width 0.1524)
				(type default)
			)
			(layer "F.SilkS")
		)
		(fp_line
			(start -0.7874 0.4064)
			(end -0.7874 -0.4064)
			(stroke
				(width 0.1524)
				(type default)
			)
			(layer "F.SilkS")
		)
		(fp_line
			(start 0.7874 -0.4064)
			(end 0.7874 0.4064)
			(stroke
				(width 0.1524)
				(type default)
			)
			(layer "F.SilkS")
		)
		(fp_line
			(start 0.7874 0.4064)
			(end -0.7874 0.4064)
			(stroke
				(width 0.1524)
				(type default)
			)
			(layer "F.SilkS")
		)
		(fp_line
			(start -0.67945 -0.305054)
			(end -0.12065 -0.305054)
			(stroke
				(width 0.1)
				(type default)
			)
			(layer "F.Fab")
		)
		(fp_line
			(start -0.67945 0.3048)
			(end -0.67945 -0.305054)
			(stroke
				(width 0.1)
				(type default)
			)
			(layer "F.Fab")
		)
		(fp_line
			(start -0.12065 -0.305054)
			(end -0.12065 -0.2794)
			(stroke
				(width 0.1)
				(type default)
			)
			(layer "F.Fab")
		)
		(fp_line
			(start -0.12065 -0.2794)
			(end 0.12065 -0.2794)
			(stroke
				(width 0.1)
				(type default)
			)
			(layer "F.Fab")
		)
		(fp_line
			(start -0.12065 0.2794)
			(end -0.12065 0.3048)
			(stroke
				(width 0.1)
				(type default)
			)
			(layer "F.Fab")
		)
		(fp_line
			(start -0.12065 0.3048)
			(end -0.67945 0.3048)
			(stroke
				(width 0.1)
				(type default)
			)
			(layer "F.Fab")
		)
		(fp_line
			(start 0.120396 0.2794)
			(end -0.12065 0.2794)
			(stroke
				(width 0.1)
				(type default)
			)
			(layer "F.Fab")
		)
		(fp_line
			(start 0.120396 0.3048)
			(end 0.120396 0.2794)
			(stroke
				(width 0.1)
				(type default)
			)
			(layer "F.Fab")
		)
		(fp_line
			(start 0.12065 -0.3048)
			(end 0.67945 -0.3048)
			(stroke
				(width 0.1)
				(type default)
			)
			(layer "F.Fab")
		)
		(fp_line
			(start 0.12065 -0.2794)
			(end 0.12065 -0.3048)
			(stroke
				(width 0.1)
				(type default)
			)
			(layer "F.Fab")
		)
		(fp_line
			(start 0.67945 -0.3048)
			(end 0.67945 0.3048)
			(stroke
				(width 0.1)
				(type default)
			)
			(layer "F.Fab")
		)
		(fp_line
			(start 0.67945 0.3048)
			(end 0.120396 0.3048)
			(stroke
				(width 0.1)
				(type default)
			)
			(layer "F.Fab")
		)
		(pad "1" smd circle
			(at -0.40005 0)
			(size 0 0)
			(layers "F.Cu" "F.Mask" "F.Paste")
			(net "P12V_PSU_FUSE")
		)
		(pad "2" smd circle
			(at 0.40005 0)
			(size 0 0)
			(layers "F.Cu" "F.Mask" "F.Paste")
			(net "HSC_EN")
		)
	)
	(footprint ""
		(layer "F.Cu")
		(at 227.949252 -290.341812 89.946)
		(property "Reference" "PR6526"
			(at 0 0 89.946)
			(layer "F.SilkS")
			(hide yes)
			(effects
				(font
					(size 1.27 1.27)
				)
			)
		)
		(property "Value" ""
			(at 0 0 89.946)
			(layer "F.Fab")
			(effects
				(font
					(size 1.27 1.27)
				)
			)
		)
		(duplicate_pad_numbers_are_jumpers no)
		(fp_line
			(start -0.787275 -0.40642)
			(end 0.787525 -0.40638)
			(stroke
				(width 0.1524)
				(type default)
			)
			(layer "F.SilkS")
		)
		(fp_line
			(start 0.787525 -0.40638)
			(end 0.787275 0.40642)
			(stroke
				(width 0.1524)
				(type default)
			)
			(layer "F.SilkS")
		)
		(fp_line
			(start -0.787525 0.40638)
			(end -0.787275 -0.40642)
			(stroke
				(width 0.1524)
				(type default)
			)
			(layer "F.SilkS")
		)
		(fp_line
			(start 0.787275 0.40642)
			(end -0.787525 0.40638)
			(stroke
				(width 0.1524)
				(type default)
			)
			(layer "F.SilkS")
		)
		(fp_line
			(start -0.679484 -0.305176)
			(end -0.120683 -0.30494)
			(stroke
				(width 0.1)
				(type default)
			)
			(layer "F.Fab")
		)
		(fp_line
			(start -0.120683 -0.30494)
			(end -0.120659 -0.279286)
			(stroke
				(width 0.1)
				(type default)
			)
			(layer "F.Fab")
		)
		(fp_line
			(start 0.120617 -0.304914)
			(end 0.679417 -0.304678)
			(stroke
				(width 0.1)
				(type default)
			)
			(layer "F.Fab")
		)
		(fp_line
			(start 0.679417 -0.304678)
			(end 0.679484 0.304922)
			(stroke
				(width 0.1)
				(type default)
			)
			(layer "F.Fab")
		)
		(fp_line
			(start 0.120641 -0.279514)
			(end 0.120617 -0.304914)
			(stroke
				(width 0.1)
				(type default)
			)
			(layer "F.Fab")
		)
		(fp_line
			(start -0.120659 -0.279286)
			(end 0.120641 -0.279514)
			(stroke
				(width 0.1)
				(type default)
			)
			(layer "F.Fab")
		)
		(fp_line
			(start 0.120405 0.279287)
			(end -0.120641 0.279514)
			(stroke
				(width 0.1)
				(type default)
			)
			(layer "F.Fab")
		)
		(fp_line
			(start -0.120641 0.279514)
			(end -0.120617 0.304914)
			(stroke
				(width 0.1)
				(type default)
			)
			(layer "F.Fab")
		)
		(fp_line
			(start -0.679417 0.304678)
			(end -0.679484 -0.305176)
			(stroke
				(width 0.1)
				(type default)
			)
			(layer "F.Fab")
		)
		(fp_line
			(start 0.120429 0.304687)
			(end 0.120405 0.279287)
			(stroke
				(width 0.1)
				(type default)
			)
			(layer "F.Fab")
		)
		(fp_line
			(start -0.120617 0.304914)
			(end -0.679417 0.304678)
			(stroke
				(width 0.1)
				(type default)
			)
			(layer "F.Fab")
		)
		(fp_line
			(start 0.679484 0.304922)
			(end 0.120429 0.304687)
			(stroke
				(width 0.1)
				(type default)
			)
			(layer "F.Fab")
		)
		(pad "1" smd circle
			(at -0.40005 0 89.946)
			(size 0 0)
			(layers "F.Cu" "F.Mask" "F.Paste")
			(net "P1V8_RETIMER_CPU1_FB")
		)
		(pad "2" smd circle
			(at 0.40005 0 89.946)
			(size 0 0)
			(layers "F.Cu" "F.Mask" "F.Paste")
			(net "GND")
		)
	)
	(footprint ""
		(layer "F.Cu")
		(at 26.226516 -39.037514)
		(property "Reference" "C1106"
			(at 0 0 0)
			(layer "F.SilkS")
			(hide yes)
			(effects
				(font
					(size 1.27 1.27)
				)
			)
		)
		(property "Value" ""
			(at 0 0 0)
			(layer "F.Fab")
			(effects
				(font
					(size 1.27 1.27)
				)
			)
		)
		(duplicate_pad_numbers_are_jumpers no)
		(fp_line
			(start -0.7874 -0.4064)
			(end 0.7874 -0.4064)
			(stroke
				(width 0.1524)
				(type default)
			)
			(layer "F.SilkS")
		)
		(fp_line
			(start -0.7874 0.4064)
			(end -0.7874 -0.4064)
			(stroke
				(width 0.1524)
				(type default)
			)
			(layer "F.SilkS")
		)
		(fp_line
			(start 0.7874 -0.4064)
			(end 0.7874 0.4064)
			(stroke
				(width 0.1524)
				(type default)
			)
			(layer "F.SilkS")
		)
		(fp_line
			(start 0.7874 0.4064)
			(end -0.7874 0.4064)
			(stroke
				(width 0.1524)
				(type default)
			)
			(layer "F.SilkS")
		)
		(fp_line
			(start -0.67945 -0.305054)
			(end -0.12065 -0.305054)
			(stroke
				(width 0.1)
				(type default)
			)
			(layer "F.Fab")
		)
		(fp_line
			(start -0.67945 0.3048)
			(end -0.67945 -0.305054)
			(stroke
				(width 0.1)
				(type default)
			)
			(layer "F.Fab")
		)
		(fp_line
			(start -0.12065 -0.305054)
			(end -0.12065 -0.2794)
			(stroke
				(width 0.1)
				(type default)
			)
			(layer "F.Fab")
		)
		(fp_line
			(start -0.12065 -0.2794)
			(end 0.12065 -0.2794)
			(stroke
				(width 0.1)
				(type default)
			)
			(layer "F.Fab")
		)
		(fp_line
			(start -0.12065 0.2794)
			(end -0.12065 0.3048)
			(stroke
				(width 0.1)
				(type default)
			)
			(layer "F.Fab")
		)
		(fp_line
			(start -0.12065 0.3048)
			(end -0.67945 0.3048)
			(stroke
				(width 0.1)
				(type default)
			)
			(layer "F.Fab")
		)
		(fp_line
			(start 0.120396 0.2794)
			(end -0.12065 0.2794)
			(stroke
				(width 0.1)
				(type default)
			)
			(layer "F.Fab")
		)
		(fp_line
			(start 0.120396 0.3048)
			(end 0.120396 0.2794)
			(stroke
				(width 0.1)
				(type default)
			)
			(layer "F.Fab")
		)
		(fp_line
			(start 0.12065 -0.3048)
			(end 0.67945 -0.3048)
			(stroke
				(width 0.1)
				(type default)
			)
			(layer "F.Fab")
		)
		(fp_line
			(start 0.12065 -0.2794)
			(end 0.12065 -0.3048)
			(stroke
				(width 0.1)
				(type default)
			)
			(layer "F.Fab")
		)
		(fp_line
			(start 0.67945 -0.3048)
			(end 0.67945 0.3048)
			(stroke
				(width 0.1)
				(type default)
			)
			(layer "F.Fab")
		)
		(fp_line
			(start 0.67945 0.3048)
			(end 0.120396 0.3048)
			(stroke
				(width 0.1)
				(type default)
			)
			(layer "F.Fab")
		)
		(pad "1" smd circle
			(at -0.40005 0)
			(size 0 0)
			(layers "F.Cu" "F.Mask" "F.Paste")
			(net "P3V3_AUX")
		)
		(pad "2" smd circle
			(at 0.40005 0)
			(size 0 0)
			(layers "F.Cu" "F.Mask" "F.Paste")
			(net "GND")
		)
	)
	(footprint ""
		(layer "F.Cu")
		(at 370.889276 -178.0921 90)
		(property "Reference" "PC490"
			(at 0 0 90)
			(layer "F.SilkS")
			(hide yes)
			(effects
				(font
					(size 1.27 1.27)
				)
			)
		)
		(property "Value" ""
			(at 0 0 90)
			(layer "F.Fab")
			(effects
				(font
					(size 1.27 1.27)
				)
			)
		)
		(duplicate_pad_numbers_are_jumpers no)
		(fp_line
			(start 0.7874 -0.4064)
			(end 0.7874 0.4064)
			(stroke
				(width 0.1524)
				(type default)
			)
			(layer "F.SilkS")
		)
		(fp_line
			(start -0.7874 -0.4064)
			(end 0.7874 -0.4064)
			(stroke
				(width 0.1524)
				(type default)
			)
			(layer "F.SilkS")
		)
		(fp_line
			(start 0.7874 0.4064)
			(end -0.7874 0.4064)
			(stroke
				(width 0.1524)
				(type default)
			)
			(layer "F.SilkS")
		)
		(fp_line
			(start -0.7874 0.4064)
			(end -0.7874 -0.4064)
			(stroke
				(width 0.1524)
				(type default)
			)
			(layer "F.SilkS")
		)
		(fp_line
			(start -0.12065 -0.305054)
			(end -0.12065 -0.2794)
			(stroke
				(width 0.1)
				(type default)
			)
			(layer "F.Fab")
		)
		(fp_line
			(start -0.67945 -0.305054)
			(end -0.12065 -0.305054)
			(stroke
				(width 0.1)
				(type default)
			)
			(layer "F.Fab")
		)
		(fp_line
			(start 0.67945 -0.3048)
			(end 0.67945 0.3048)
			(stroke
				(width 0.1)
				(type default)
			)
			(layer "F.Fab")
		)
		(fp_line
			(start 0.12065 -0.3048)
			(end 0.67945 -0.3048)
			(stroke
				(width 0.1)
				(type default)
			)
			(layer "F.Fab")
		)
		(fp_line
			(start 0.12065 -0.2794)
			(end 0.12065 -0.3048)
			(stroke
				(width 0.1)
				(type default)
			)
			(layer "F.Fab")
		)
		(fp_line
			(start -0.12065 -0.2794)
			(end 0.12065 -0.2794)
			(stroke
				(width 0.1)
				(type default)
			)
			(layer "F.Fab")
		)
		(fp_line
			(start 0.120396 0.2794)
			(end -0.12065 0.2794)
			(stroke
				(width 0.1)
				(type default)
			)
			(layer "F.Fab")
		)
		(fp_line
			(start -0.12065 0.2794)
			(end -0.12065 0.3048)
			(stroke
				(width 0.1)
				(type default)
			)
			(layer "F.Fab")
		)
		(fp_line
			(start 0.67945 0.3048)
			(end 0.120396 0.3048)
			(stroke
				(width 0.1)
				(type default)
			)
			(layer "F.Fab")
		)
		(fp_line
			(start 0.120396 0.3048)
			(end 0.120396 0.2794)
			(stroke
				(width 0.1)
				(type default)
			)
			(layer "F.Fab")
		)
		(fp_line
			(start -0.12065 0.3048)
			(end -0.67945 0.3048)
			(stroke
				(width 0.1)
				(type default)
			)
			(layer "F.Fab")
		)
		(fp_line
			(start -0.67945 0.3048)
			(end -0.67945 -0.305054)
			(stroke
				(width 0.1)
				(type default)
			)
			(layer "F.Fab")
		)
		(pad "1" smd circle
			(at -0.40005 0 90)
			(size 0 0)
			(layers "F.Cu" "F.Mask" "F.Paste")
			(net "SW_PVDDCR_CPU0_P0_BOOT2_RC")
		)
		(pad "2" smd circle
			(at 0.40005 0 90)
			(size 0 0)
			(layers "F.Cu" "F.Mask" "F.Paste")
			(net "SW_PVDDCR_CPU0_P0_PH2")
		)
	)
)
